# BASEBOARD_FAB2 (Tioga Pass) — schematic netlist excerpt (pin names and nets, part order shuffled) for the footprints in the layout excerpt that follows; sources: Cadence DE-HDL packaged netlist, KiCad conversion of Wiwynn_Tioga_Pass_MB.brd

R1D54  RES  68.1K 1% EMPTY  pkg 0402  page 208 : A = VR_PVCCIN_CPU1_PH4_OCSET ; B = GND

(kicad_pcb
	(version 20260206)
	(generator "pcbnew")
	(generator_version "10.0")
	(general
		(thickness 1.6)
		(legacy_teardrops no)
	)
	(paper "A4")
	(title_block
		(title "Wiwynn_Tioga_Pass_MB.brd")
		(comment 1 "Tioga Pass / footprints 857-857 of 4770")
	)
	(layers
		(0 "F.Cu" signal "TOP")
		(4 "In1.Cu" signal "L2GND")
		(6 "In2.Cu" signal "L3")
		(8 "In3.Cu" signal "L4GND")
		(10 "In4.Cu" signal "L5")
		(12 "In5.Cu" signal "L6GND")
		(14 "In6.Cu" signal "L7VCC")
		(16 "In7.Cu" signal "L8VCC")
		(18 "In8.Cu" signal "L9GND")
		(20 "In9.Cu" signal "L10")
		(22 "In10.Cu" signal "L11GND")
		(24 "In11.Cu" signal "L12")
		(26 "In12.Cu" signal "L13GND")
		(2 "B.Cu" signal "BOTTOM")
		(9 "F.Adhes" user "F.Adhesive")
		(11 "B.Adhes" user "B.Adhesive")
		(13 "F.Paste" user "Package Geometry/Pastemask Top")
		(15 "B.Paste" user "Package Geometry/Pastemask Bottom")
		(5 "F.SilkS" user "Ref Des/Silkscreen Top")
		(7 "B.SilkS" user "Ref Des/Silkscreen Bottom")
		(1 "F.Mask" user "Board Geometry/Soldermask Top")
		(3 "B.Mask" user "Board Geometry/Soldermask Bottom")
		(17 "Dwgs.User" user "User.Drawings")
		(19 "Cmts.User" user "User.Comments")
		(21 "Eco1.User" user "User.Eco1")
		(23 "Eco2.User" user "User.Eco2")
		(25 "Edge.Cuts" user "Board Geometry/Outline")
		(27 "Margin" user)
		(31 "F.CrtYd" user "Package Geometry/Place Bound Top")
		(29 "B.CrtYd" user "Package Geometry/Place Bound Bottom")
		(35 "F.Fab" user "Ref Des/Assembly Top")
		(33 "B.Fab" user "Ref Des/Assembly Bottom")
	)
	(footprint ""
		(layer "F.Cu")
		(at 28.438348 -80.3148 -90)
		(property "Reference" "R1D54"
			(at 0 0 270)
			(layer "F.SilkS")
			(hide yes)
			(effects
				(font
					(size 1.27 1.27)
				)
			)
		)
		(property "Value" ""
			(at 0 0 270)
			(layer "F.Fab")
			(effects
				(font
					(size 1.27 1.27)
				)
			)
		)
		(duplicate_pad_numbers_are_jumpers no)
		(fp_poly
			(pts
				(xy -0.2794 -0.1016) (xy 0.2794 -0.1016) (xy 0.2794 0.9906) (xy -0.2794 0.9906)
			)
			(stroke
				(width 0)
				(type default)
			)
			(fill no)
			(layer "F.CrtYd")
		)
		(fp_line
			(start -0.2794 0.9906)
			(end 0.2794 0.9906)
			(stroke
				(width 0.1)
				(type default)
			)
			(layer "F.Fab")
		)
		(fp_line
			(start 0.2794 0.9906)
			(end 0.2794 -0.1016)
			(stroke
				(width 0.1)
				(type default)
			)
			(layer "F.Fab")
		)
		(fp_line
			(start -0.2794 -0.1016)
			(end -0.2794 0.9906)
			(stroke
				(width 0.1)
				(type default)
			)
			(layer "F.Fab")
		)
		(fp_line
			(start 0.2794 -0.1016)
			(end -0.2794 -0.1016)
			(stroke
				(width 0.1)
				(type default)
			)
			(layer "F.Fab")
		)
		(pad "1" smd rect
			(at 0 0 270)
			(size 0.508 0.508)
			(layers "F.Cu" "F.Mask" "F.Paste")
			(net "VR_PVCCIN_CPU1_PH4_OCSET")
		)
		(pad "2" smd rect
			(at 0 0.889 270)
			(size 0.508 0.508)
			(layers "F.Cu" "F.Mask" "F.Paste")
			(net "GND")
		)
		(zone
			(layer "F.Cu")
			(hatch none 0.5)
			(connect_pads
				(clearance 0)
			)
			(min_thickness 0.25)
			(keepout
				(tracks not_allowed)
				(vias allowed)
				(pads allowed)
				(copperpour not_allowed)
				(footprints allowed)
			)
			(placement
				(enabled no)
				(sheetname "")
			)
			(fill
				(thermal_gap 0.5)
				(thermal_bridge_width 0.5)
				(island_removal_mode 0)
			)
			(polygon
				(pts
					(xy 27.803348 -80.5688) (xy 27.803348 -80.0608) (xy 28.184348 -80.0608) (xy 28.184348 -80.5688)
				)
			)
		)
		(zone
			(layer "F.Cu")
			(hatch none 0.5)
			(connect_pads
				(clearance 0)
			)
			(min_thickness 0.25)
			(keepout
				(tracks allowed)
				(vias not_allowed)
				(pads allowed)
				(copperpour not_allowed)
				(footprints allowed)
			)
			(placement
				(enabled no)
				(sheetname "")
			)
			(fill
				(thermal_gap 0.5)
				(thermal_bridge_width 0.5)
				(island_removal_mode 0)
			)
			(polygon
				(pts
					(xy 28.184348 -80.5688) (xy 28.184348 -80.0608) (xy 27.803348 -80.0608) (xy 27.803348 -80.5688)
				)
			)
		)
	)
)
